FILE_TYPE = CONNECTIVITY;
{Allegro Design Entry HDL 17.4-2019 S026 (4007227) 1/17/2022}
"PAGE_NUMBER" = 245;
0"NC";
1"GND\g";
2"GND\g";
3"GND\g";
4"GND\g";
5"GND\g";
6"GND\g";
7"P12V_AUX\g";
8"GND\g";
9"GND\g";
10"GND\g";
11"P3V3_AUX\g";
12"P12V_AUX\g";
13"P3V3_AUX\g";
14"GND\g";
15"GND\g";
16"GND\g";
17"PWRGD_P3V3_AUX_R1";
18"P3V3_AUX_SS";
19"P3V3_AUX_VOS";
20"NC_PU9_2";
21"SW_P3V3_AUX_BOOT";
22"NC_PU9_1";
23"NC_HICCUP";
24"P3V3_AUX_ILIM";
25"PWRGD_P5V_AUX";
26"SW_P3V3_AUX_BOOT_R";
27"SW_P3V3_AUX_BOOTR";
28"NC_PU9_3";
29"NC_PU9_4";
30"P3V3_AUX_MODE";
31"SW_P3V3_AUX_SW";
32"PWRGD_P3V3_AUX";
33"P3V3_AUX_FB";
34"P3V3_AUX_VCC";
35"P3V3_AUX_EN";
36"P3V3_AUX_VDRV";
37"SW_P3V3_AUX_FLT";
38"P3V3_AUX\g";
39"GND\g";
40"GND\g";
41"P12V_AUX\g";
42"GND\g";
43"GND\g";
%"GND"
"1","(-3300,-1475)","0","pure_quanta_power","I1";
;
CDS_LIB"pure_quanta_power"
SIZE"1B"
HDL_POWER"GND";
"A<SIZE-1..0>\NAC"1;
%"Q_RES"
"2","(-2150,-975)","0","pure_quanta","I10";
;
LOCATION"PR832"
$SEC"1"
CDS_SEC"1"
PACK_TYPE"0402LF"
VALUE"0"
TOLERANCE"5%"
MATERIAL"CHIP"
WATTAGE"1/16W"
CDS_LIB"pure_quanta"
PART_NUMBER"CS00002JB13";
"A"
$PN"1"30;
"B"
$PN"2"16;
%"Q_RES"
"2","(-2800,-600)","0","pure_quanta","I11";
;
LOCATION"R1571"
$SEC"1"
CDS_SEC"1"
PACK_TYPE"0402LF"
MATERIAL"CHIP"
WATTAGE"1/16W"
TOLERANCE"5%"
VALUE"0"
CDS_LIB"pure_quanta"
PART_NUMBER"CS00002JB13"
LOCATION"R1571";
"A"
$PN"1"25;
"B"
$PN"2"35;
%"Q_CAP"
"1","(-2050,-375)","0","pure_quanta","I12";
;
LOCATION"PC581"
$SEC"1"
CDS_SEC"1"
PACK_TYPE"C0603"
VOLTAGE"16V"
VALUE"4.7UF"
MATERIAL"X6S"
TOLERANCE"10%"
CDS_LIB"pure_quanta"
PART_NUMBER"CH5473KE902";
"B"
$PN"2"2;
"A"
$PN"1"36;
%"GND"
"1","(-2050,-600)","0","pure_quanta_power","I13";
;
SIZE"1B"
CDS_LIB"pure_quanta_power"
HDL_POWER"GND";
"A<SIZE-1..0>\NAC"2;
%"GND"
"1","(-1750,-1275)","0","pure_quanta_power","I14";
;
CDS_LIB"pure_quanta_power"
SIZE"1B"
HDL_POWER"GND";
"A<SIZE-1..0>\NAC"3;
%"Q_RES"
"2","(-1750,-1075)","0","pure_quanta","I15";
;
LOCATION"PR833"
$SEC"1"
CDS_SEC"1"
TOLERANCE"1%"
PACK_TYPE"0402LF"
VALUE"1.5K"
MATERIAL"EMPTY"
WATTAGE"1/16W"
CDS_LIB"pure_quanta"
PART_NUMBER"CS21502FB07";
"A"
$PN"1"18;
"B"
$PN"2"3;
%"GND"
"1","(-1350,-1375)","0","pure_quanta_power","I16";
;
SIZE"1B"
CDS_LIB"pure_quanta_power"
HDL_POWER"GND";
"A<SIZE-1..0>\NAC"4;
%"Q_RES"
"2","(-1350,-1175)","0","pure_quanta","I17";
;
LOCATION"PR834"
$SEC"1"
CDS_SEC"1"
WATTAGE"1/16W"
TOLERANCE"1%"
PACK_TYPE"0402LF"
MATERIAL"CHIP"
VALUE"21.5K"
CDS_LIB"pure_quanta"
PART_NUMBER"CS32152FB04";
"A"
$PN"1"24;
"B"
$PN"2"4;
%"GND"
"1","(-1625,-600)","0","pure_quanta_power","I18";
;
CDS_LIB"pure_quanta_power"
SIZE"1B"
HDL_POWER"GND";
"A<SIZE-1..0>\NAC"5;
%"Q_CAP"
"1","(-1625,-375)","0","pure_quanta","I19";
;
LOCATION"PC591"
$SEC"1"
CDS_SEC"1"
PACK_TYPE"C0603"
VALUE"2.2UF"
VOLTAGE"16V"
TOLERANCE"10%"
MATERIAL"X6S"
CDS_LIB"pure_quanta"
PART_NUMBER"CH5223KE901";
"B"
$PN"2"5;
"A"
$PN"1"34;
%"Q_RES"
"2","(-3300,-1175)","0","pure_quanta","I2";
;
LOCATION"R3118"
$SEC"1"
CDS_SEC"1"
PACK_TYPE"0402LF"
WATTAGE"1/16W"
VALUE"86.6K"
TOLERANCE"1%"
MATERIAL"EMPTY"
CDS_LIB"pure_quanta"
PART_NUMBER"CS38662FB05";
"A"
$PN"1"35;
"B"
$PN"2"1;
%"Q_RES"
"1","(-1800,-150)","0","pure_quanta","I20";
;
LOCATION"PR8389"
$SEC"1"
CDS_SEC"1"
WATTAGE"1/16W"
TOLERANCE"1%"
PACK_TYPE"0402LF"
MATERIAL"CHIP"
VALUE"1"
CDS_LIB"pure_quanta"
PART_NUMBER"CS-1002FB04";
"B"
$PN"2"34;
"A"
$PN"1"36;
%"NCP3284AMNTXG"
"1","(-100,-500)","0","pure_quanta","I21";
;
LOCATION"PU9"
$SEC"1"
CDS_SEC"1"
VALUE"NCP3284AMNTXG"
MATERIAL"IC"
PART_TYPE"SMLF"
CDS_LIB"pure_quanta"
NEEDS_NO_SIZE"TRUE"
CDS_LMAN_SYM_OUTLINE"-300,700,250,-700"
PART_NUMBER"AL003284002";
"GL2"
$PN"37"29;
"SS"
$PN"29"18;
"GL1"
$PN"6"28;
"VDRV"
$PN"5"36;
"EN"
$PN"27"35;
"AGND"
$PN"32"40;
"VOS"
$PN"28"19;
"PGOOD"
$PN"2"17;
"PVIN"
$PN"20_24"37;
"SW"
$PN"11_18"31;
"NC1"
$PN"33"22;
"PGND"
$PN"7_10-19"40;
"HICCUP# \B"
$PN"35"23;
"VSNS-"
$PN"31"9;
"VCC"
$PN"4"34;
"PHASE"
$PN"25"27;
"ILIM"
$PN"1"24;
"BOOT"
$PN"26"21;
"FB"
$PN"30"33;
"VIN"
$PN"3"41;
"MODE||FSET"
$PN"36"30;
"NC2"
$PN"34"20;
%"GND"
"1","(-4525,850)","0","pure_quanta_power","I22";
;
CDS_LIB"pure_quanta_power"
SIZE"1B"
HDL_POWER"GND";
"A<SIZE-1..0>\NAC"6;
%"Q_CAP"
"1","(-4525,1100)","0","pure_quanta","I23";
;
LOCATION"PC1649"
$SEC"1"
CDS_SEC"1"
TOLERANCE"10%"
VALUE"0.1UF"
MATERIAL"X6S"
VOLTAGE"25V"
PACK_TYPE"C0402"
CDS_LIB"pure_quanta"
PART_NUMBER"CH4104KEB00";
"B"
$PN"2"6;
"A"
$PN"1"7;
%"Q_INDUCTOR"
"1","(-4300,1325)","0","pure_quanta","I24";
;
LOCATION"PL8045"
$SEC"1"
CDS_SEC"1"
PACK_TYPE"SMLF"
MATERIAL"IND"
VALUE"100NH/16A"
CDS_LIB"pure_quanta"
NEEDS_NO_SIZE"TRUE"
PART_NUMBER"CV+10G0MZ04";
"1"
$PN"1"7;
"2"
$PN"2"37;
%"UNIVERSAL_POWER"
"1","(-4525,1725)","0","pure_quanta_power","I25";
;
HDL_POWER"P12V_AUX"
CDS_LIB"pure_quanta_power";
"A"7;
%"Q_CAP"
"1","(-4050,450)","0","pure_quanta","I26";
;
LOCATION"PC2260"
$SEC"1"
CDS_SEC"1"
PACK_TYPE"C0805"
TOLERANCE"20%"
MATERIAL"X6S"
VALUE"22UF"
VOLTAGE"16V"
CDS_LIB"pure_quanta"
PART_NUMBER"CH6223MEA01";
"B"
$PN"2"42;
"A"
$PN"1"37;
%"Q_CAP"
"1","(-3725,450)","0","pure_quanta","I27";
;
LOCATION"PC2261"
$SEC"1"
CDS_SEC"1"
VALUE"22UF"
TOLERANCE"20%"
VOLTAGE"16V"
MATERIAL"X6S"
PACK_TYPE"C0805"
CDS_LIB"pure_quanta"
PART_NUMBER"CH6223MEA01";
"B"
$PN"2"42;
"A"
$PN"1"37;
%"GND"
"1","(-3975,725)","0","pure_quanta_power","I28";
;
SIZE"1B"
CDS_LIB"pure_quanta_power"
HDL_POWER"GND";
"A<SIZE-1..0>\NAC"43;
%"Q_CAPP"
"1","(-3975,1100)","0","pure_quanta","I29";
;
LOCATION"PC3"
$SEC"1"
CDS_SEC"1"
VOLTAGE"16V"
TOLERANCE"20%"
VALUE"270UF"
PACK_TYPE"THLF"
MATERIAL"OSCON"
CDS_LIB"pure_quanta"
PART_NUMBER"CC72703MD38"
LOCATION"PC3";
"A"
$PN"1"37;
"B"
$PN"2"43;
%"GND"
"1","(-4050,100)","0","pure_quanta_power","I3";
;
SIZE"1B"
CDS_LIB"pure_quanta_power"
HDL_POWER"GND";
"A<SIZE-1..0>\NAC"42;
%"Q_CAPP"
"1","(-3675,1100)","0","pure_quanta","I30";
;
LOCATION"PC566"
$SEC"1"
CDS_SEC"1"
MATERIAL"OSCON"
VOLTAGE"16V"
VALUE"270UF"
TOLERANCE"20%"
PACK_TYPE"THLF"
CDS_LIB"pure_quanta"
PART_NUMBER"CC72703MD38"
LOCATION"PC566";
"A"
$PN"1"37;
"B"
$PN"2"43;
%"Q_CAP"
"1","(-3400,450)","0","pure_quanta","I31";
;
LOCATION"PC2262"
$SEC"1"
CDS_SEC"1"
VOLTAGE"16V"
PACK_TYPE"C0805"
MATERIAL"X6S"
TOLERANCE"20%"
VALUE"22UF"
CDS_LIB"pure_quanta"
PART_NUMBER"CH6223MEA01";
"B"
$PN"2"42;
"A"
$PN"1"37;
%"Q_CAP"
"1","(-3350,1100)","0","pure_quanta","I32";
;
LOCATION"PC8567"
$SEC"1"
CDS_SEC"1"
MATERIAL"X6S"
TOLERANCE"20%"
VOLTAGE"16V"
VALUE"22UF"
PACK_TYPE"C0805"
CDS_LIB"pure_quanta"
PART_NUMBER"CH6223MEA01";
"B"
$PN"2"43;
"A"
$PN"1"37;
%"Q_CAP"
"1","(-3075,450)","0","pure_quanta","I33";
;
LOCATION"PC2263"
$SEC"1"
CDS_SEC"1"
PACK_TYPE"C0805"
MATERIAL"X6S"
TOLERANCE"20%"
VOLTAGE"16V"
VALUE"22UF"
CDS_LIB"pure_quanta"
PART_NUMBER"CH6223MEA01";
"B"
$PN"2"42;
"A"
$PN"1"37;
%"Q_CAP"
"1","(-2750,450)","0","pure_quanta","I34";
;
LOCATION"PC2342"
$SEC"1"
CDS_SEC"1"
PACK_TYPE"C0805"
TOLERANCE"20%"
MATERIAL"X6S"
VOLTAGE"16V"
VALUE"22UF"
CDS_LIB"pure_quanta"
PART_NUMBER"CH6223MEA01";
"B"
$PN"2"42;
"A"
$PN"1"37;
%"Q_CAP"
"1","(-3025,1100)","0","pure_quanta","I35";
;
LOCATION"PC570"
$SEC"1"
CDS_SEC"1"
VOLTAGE"16V"
VALUE"22UF"
PACK_TYPE"C0805"
TOLERANCE"20%"
MATERIAL"X6S"
CDS_LIB"pure_quanta"
PART_NUMBER"CH6223MEA01";
"B"
$PN"2"43;
"A"
$PN"1"37;
%"Q_CAP"
"1","(-2700,1100)","0","pure_quanta","I36";
;
LOCATION"PC571"
$SEC"1"
CDS_SEC"1"
MATERIAL"X6S"
VOLTAGE"16V"
VALUE"22UF"
PACK_TYPE"C0805"
TOLERANCE"20%"
CDS_LIB"pure_quanta"
PART_NUMBER"CH6223MEA01";
"B"
$PN"2"43;
"A"
$PN"1"37;
%"Q_CAP"
"1","(-2425,450)","0","pure_quanta","I37";
;
LOCATION"PC2343"
$SEC"1"
CDS_SEC"1"
MATERIAL"X6S"
VALUE"22UF"
PACK_TYPE"C0805"
VOLTAGE"16V"
TOLERANCE"20%"
CDS_LIB"pure_quanta"
PART_NUMBER"CH6223MEA01";
"B"
$PN"2"42;
"A"
$PN"1"37;
%"Q_CAP"
"1","(-2100,450)","0","pure_quanta","I38";
;
LOCATION"PC2344"
$SEC"1"
CDS_SEC"1"
VOLTAGE"16V"
PACK_TYPE"C0805"
TOLERANCE"20%"
MATERIAL"X6S"
VALUE"22UF"
CDS_LIB"pure_quanta"
PART_NUMBER"CH6223MEA01";
"B"
$PN"2"42;
"A"
$PN"1"37;
%"Q_CAP"
"1","(-2375,1100)","0","pure_quanta","I39";
;
LOCATION"PC576"
$SEC"1"
CDS_SEC"1"
MATERIAL"X6S"
PACK_TYPE"C0805"
VALUE"22UF"
TOLERANCE"20%"
VOLTAGE"16V"
CDS_LIB"pure_quanta"
PART_NUMBER"CH6223MEA01";
"B"
$PN"2"43;
"A"
$PN"1"37;
%"Q_RES"
"2","(-3300,-600)","0","pure_quanta","I4";
;
LOCATION"R3117"
$SEC"1"
CDS_SEC"1"
TOLERANCE"5%"
VALUE"510K"
WATTAGE"1/16W"
MATERIAL"EMPTY"
PACK_TYPE"0402LF"
CDS_LIB"pure_quanta"
PART_NUMBER"CS45102JB03";
"A"
$PN"1"12;
"B"
$PN"2"35;
%"Q_CAP"
"1","(-2050,1100)","0","pure_quanta","I40";
;
LOCATION"PC8071"
$SEC"1"
CDS_SEC"1"
PACK_TYPE"C0805"
TOLERANCE"20%"
MATERIAL"X6S"
VOLTAGE"16V"
VALUE"22UF"
CDS_LIB"pure_quanta"
PART_NUMBER"CH6223MEA01";
"B"
$PN"2"43;
"A"
$PN"1"37;
%"Q_CAP"
"1","(-1725,1100)","0","pure_quanta","I41";
;
LOCATION"PC577"
$SEC"1"
CDS_SEC"1"
PACK_TYPE"0402"
TOLERANCE"10%"
VALUE"0.1UF"
VOLTAGE"25V"
MATERIAL"X7R"
CDS_LIB"pure_quanta"
PART_NUMBER"CH4104K1B00";
"B"
$PN"2"43;
"A"
$PN"1"37;
%"UNIVERSAL_POWER"
"1","(-1150,1050)","0","pure_quanta_power","I42";
;
HDL_POWER"P12V_AUX"
CDS_LIB"pure_quanta_power";
"A"41;
%"GND"
"1","(-900,450)","0","pure_quanta_power","I43";
;
CDS_LIB"pure_quanta_power"
SIZE"1B"
HDL_POWER"GND";
"A<SIZE-1..0>\NAC"8;
%"Q_CAP"
"1","(-900,725)","0","pure_quanta","I44";
;
LOCATION"PC8008"
$SEC"1"
CDS_SEC"1"
PACK_TYPE"0603"
MATERIAL"X7R"
TOLERANCE"10%"
VALUE"1UF"
VOLTAGE"16V"
CDS_LIB"pure_quanta"
PART_NUMBER"TMP_QCH5103K1900";
"B"
$PN"2"8;
"A"
$PN"1"41;
%"GND"
"1","(350,-1250)","0","pure_quanta_power","I45";
;
SIZE"1B"
CDS_LIB"pure_quanta_power"
HDL_POWER"GND";
"A<SIZE-1..0>\NAC"40;
%"Q_RES"
"1","(825,-1000)","0","pure_quanta","I46";
;
LOCATION"PR836"
$SEC"1"
CDS_SEC"1"
WATTAGE"1/16W"
VALUE"1K"
TOLERANCE"1%"
PACK_TYPE"0402LF"
MATERIAL"CHIP"
CDS_LIB"pure_quanta"
PART_NUMBER"CS21002FB06";
"B"
$PN"2"11;
"A"
$PN"1"19;
%"GND"
"1","(550,-950)","1","pure_quanta_power","I47";
;
SIZE"1B"
CDS_LIB"pure_quanta_power"
HDL_POWER"GND";
"A<SIZE-1..0>\NAC"9;
%"Q_CAP"
"2","(725,-300)","0","pure_quanta","I48";
;
LOCATION"PC568"
$SEC"1"
CDS_SEC"1"
VOLTAGE"25V"
MATERIAL"X7R"
TOLERANCE"10%"
VALUE"0.22UF"
PACK_TYPE"C0402"
CDS_LIB"pure_quanta"
PART_NUMBER"CH4224K1B01";
"A"
$PN"1"27;
"B"
$PN"2"26;
%"Q_RES"
"1","(800,-100)","0","pure_quanta","I49";
;
LOCATION"PR835"
$SEC"1"
CDS_SEC"1"
WATTAGE"1/16W"
MATERIAL"CHIP"
VALUE"0"
PACK_TYPE"0402LF"
TOLERANCE"5%"
CDS_LIB"pure_quanta"
PART_NUMBER"CS00002JB13";
"B"
$PN"2"26;
"A"
$PN"1"21;
%"GND"
"1","(1200,-1750)","0","pure_quanta_power","I50";
;
CDS_LIB"pure_quanta_power"
SIZE"1B"
HDL_POWER"GND";
"A<SIZE-1..0>\NAC"10;
%"Q_RES"
"2","(1200,-1475)","0","pure_quanta","I51";
;
LOCATION"PR830"
$SEC"1"
CDS_SEC"1"
PACK_TYPE"0402LF"
MATERIAL"CHIP"
WATTAGE"1/16W"
TOLERANCE"0.1%"
VALUE"15K"
CDS_LIB"pure_quanta"
PART_NUMBER"CS31502BB03";
"A"
$PN"1"33;
"B"
$PN"2"10;
%"UNIVERSAL_POWER"
"1","(1075,-900)","0","pure_quanta_power","I52";
;
HDL_POWER"P3V3_AUX"
CDS_LIB"pure_quanta_power";
"A"11;
%"Q_CAP"
"2","(2100,-1600)","0","pure_quanta","I53";
;
LOCATION"PC569"
$SEC"1"
CDS_SEC"1"
MATERIAL"NPO"
TOLERANCE"1%"
VALUE"10PF"
VOLTAGE"50V"
PACK_TYPE"0402"
CDS_LIB"pure_quanta"
PART_NUMBER"TMP_QCH0106F0B00";
"A"
$PN"1"33;
"B"
$PN"2"38;
%"Q_RES"
"1","(2100,-1300)","0","pure_quanta","I54";
;
LOCATION"PR831"
$SEC"1"
CDS_SEC"1"
PACK_TYPE"0402LF"
TOLERANCE"0.1%"
VALUE"47K"
MATERIAL"CHIP"
WATTAGE"1/16W"
CDS_LIB"pure_quanta"
PART_NUMBER"CS34702BB05";
"B"
$PN"2"38;
"A"
$PN"1"33;
%"Q_INDUCTOR"
"1","(1425,-475)","0","pure_quanta","I55";
;
LOCATION"PL8066"
$SEC"1"
CDS_SEC"1"
MATERIAL"IND"
PACK_TYPE"SMLF"
VALUE"1.5UH/53A"
NEEDS_NO_SIZE"TRUE"
CDS_LIB"pure_quanta"
PART_NUMBER"CV-15^0MZ02";
"1"
$PN"1"31;
"2"
$PN"2"38;
%"Q_CAPP"
"1","(1650,-725)","0","pure_quanta","I57";
;
LOCATION"PC1866"
$SEC"1"
CDS_SEC"1"
PACK_TYPE"THLF"
TOLERANCE"20%"
VOLTAGE"6.3V"
MATERIAL"OSCON"
VALUE"560UF"
CDS_LIB"pure_quanta"
PART_NUMBER"CC75601MD16";
"A"
$PN"1"38;
"B"
$PN"2"39;
%"Q_CAPP"
"1","(2100,-725)","0","pure_quanta","I58";
;
LOCATION"PC1867"
$SEC"1"
CDS_SEC"1"
MATERIAL"OSCON"
VOLTAGE"6.3V"
VALUE"560UF"
PACK_TYPE"THLF"
TOLERANCE"20%"
CDS_LIB"pure_quanta"
PART_NUMBER"CC75601MD16";
"A"
$PN"1"38;
"B"
$PN"2"39;
%"Q_CAP"
"1","(2550,-700)","0","pure_quanta","I59";
;
LOCATION"PC1868"
$SEC"1"
CDS_SEC"1"
PACK_TYPE"C0805"
MATERIAL"X6S"
VOLTAGE"10V"
VALUE"22UF"
TOLERANCE"20%"
CDS_LIB"pure_quanta"
PART_NUMBER"CH6222MEA01";
"B"
$PN"2"39;
"A"
$PN"1"38;
%"P1V0_AUX"
"1","(-3300,-275)","0","pure_quanta_power","I6";
;
HDL_POWER"P12V_AUX"
CDS_LIB"pure_quanta_power";
"A"12;
%"Q_CAP"
"1","(2950,-725)","0","pure_quanta","I60";
;
LOCATION"PC1599"
$SEC"1"
CDS_SEC"1"
PACK_TYPE"C0805"
VOLTAGE"10V"
VALUE"22UF"
MATERIAL"X6S"
TOLERANCE"20%"
CDS_LIB"pure_quanta"
PART_NUMBER"CH6222MEA01";
"B"
$PN"2"39;
"A"
$PN"1"38;
%"GND"
"1","(3725,-1100)","0","pure_quanta_power","I61";
;
CDS_LIB"pure_quanta_power"
SIZE"1B"
HDL_POWER"GND";
"A<SIZE-1..0>\NAC"39;
%"Q_CAP"
"1","(3325,-725)","0","pure_quanta","I62";
;
LOCATION"PC1600"
$SEC"1"
CDS_SEC"1"
VALUE"22UF"
PACK_TYPE"C0805"
MATERIAL"X6S"
TOLERANCE"20%"
VOLTAGE"10V"
CDS_LIB"pure_quanta"
PART_NUMBER"CH6222MEA01";
"B"
$PN"2"39;
"A"
$PN"1"38;
%"Q_CAP"
"1","(3725,-725)","0","pure_quanta","I63";
;
LOCATION"PC1869"
$SEC"1"
CDS_SEC"1"
PACK_TYPE"0402"
VOLTAGE"25V"
MATERIAL"X7R"
VALUE"0.1UF"
TOLERANCE"10%"
CDS_LIB"pure_quanta"
PART_NUMBER"CH4104K1B00";
"B"
$PN"2"39;
"A"
$PN"1"38;
%"UNIVERSAL_POWER"
"1","(4175,-200)","0","pure_quanta_power","I64";
;
HDL_POWER"P3V3_AUX"
CDS_LIB"pure_quanta_power";
"A"38;
%"Q_RES"
"2","(900,450)","0","pure_quanta","I65";
;
LOCATION"PR8073"
$SEC"1"
CDS_SEC"1"
MATERIAL"CHIP"
PACK_TYPE"0402LF"
WATTAGE"1/16W"
TOLERANCE"1%"
VALUE"1K"
CDS_LIB"pure_quanta"
PART_NUMBER"CS21002FB06";
"A"
$PN"1"13;
"B"
$PN"2"17;
%"UNIVERSAL_POWER"
"1","(900,675)","0","pure_quanta_power","I66";
;
HDL_POWER"P3V3_AUX"
CDS_LIB"pure_quanta_power";
"A"13;
%"Q_RES"
"1","(1425,150)","0","pure_quanta","I67";
;
LOCATION"R6099"
$SEC"1"
CDS_SEC"1"
WATTAGE"1/16W"
VALUE"0"
TOLERANCE"5%"
MATERIAL"CHIP"
PACK_TYPE"0402LF"
CDS_LIB"pure_quanta"
PART_NUMBER"CS00002JB13";
"B"
$PN"2"32;
"A"
$PN"1"17;
%"Q_CAP"
"1","(2625,-75)","0","pure_quanta","I68";
;
LOCATION"C5015"
$SEC"1"
CDS_SEC"1"
MATERIAL"EMPTY"
VALUE"1000PF"
VOLTAGE"50V"
TOLERANCE"5%"
PACK_TYPE"0402"
CDS_LIB"pure_quanta"
PART_NUMBER"TMP_QCH21006JB10";
"B"
$PN"2"14;
"A"
$PN"1"32;
%"GND"
"1","(2625,-325)","0","pure_quanta_power","I69";
;
SIZE"1B"
CDS_LIB"pure_quanta_power"
HDL_POWER"GND";
"A<SIZE-1..0>\NAC"14;
%"GND"
"1","(-2700,-1475)","0","pure_quanta_power","I7";
;
SIZE"1B"
CDS_LIB"pure_quanta_power"
HDL_POWER"GND";
"A<SIZE-1..0>\NAC"15;
%"Q_CAP"
"1","(-1825,425)","0","pure_quanta","I70";
;
LOCATION"PC8013"
$SEC"1"
CDS_SEC"1"
TOLERANCE"20%"
MATERIAL"X6S"
VOLTAGE"16V"
VALUE"22UF"
PACK_TYPE"C0805"
CDS_LIB"pure_quanta"
PART_NUMBER"CH6223MEA01";
"B"
$PN"2"42;
"A"
$PN"1"37;
%"Q_CAP"
"1","(-1625,450)","0","pure_quanta","I71";
;
LOCATION"PC8014"
$SEC"1"
CDS_SEC"1"
MATERIAL"X6S"
VALUE"22UF"
VOLTAGE"16V"
TOLERANCE"20%"
PACK_TYPE"C0805"
CDS_LIB"pure_quanta"
PART_NUMBER"CH6223MEA01";
"B"
$PN"2"42;
"A"
$PN"1"37;
%"Q_CAP"
"1","(-2700,-1175)","2","pure_quanta","I8";
;
LOCATION"PC1870"
$SEC"1"
CDS_SEC"1"
VALUE"0.1UF"
VOLTAGE"25V"
PACK_TYPE"0402"
TOLERANCE"10%"
MATERIAL"EMPTY"
CDS_LIB"pure_quanta"
PART_NUMBER"CH4104K1B00";
"B"
$PN"2"15;
"A"
$PN"1"35;
%"GND"
"1","(-2150,-1150)","0","pure_quanta_power","I9";
;
SIZE"1B"
CDS_LIB"pure_quanta_power"
HDL_POWER"GND";
"A<SIZE-1..0>\NAC"16;
END.
